#ISCELL
  mstr_misc dns *
  *
#ISCELL
  pure_quanta quanta_title_block_c *
  *
#ISCELL
  standard offpage *
  page80_i1
#ISCELL
  standard offpage *
  page80_i10
#CELL
  pure_quanta q_res *
  page80_i100
#CELL
  pure_quanta q_res *
  page80_i101
#CELL
  pure_quanta q_res *
  page80_i102
#CELL
  pure_quanta q_res *
  page80_i103
#CELL
  pure_quanta q_res *
  page80_i104
#CELL
  pure_quanta q_res *
  page80_i105
#CELL
  pure_quanta q_res *
  page80_i106
#CELL
  pure_quanta q_res *
  page80_i107
#CELL
  pure_quanta q_res *
  page80_i108
#CELL
  pure_quanta q_res *
  page80_i109
#ISCELL
  standard offpage *
  page80_i11
#CELL
  pure_quanta q_res *
  page80_i110
#CELL
  pure_quanta q_res *
  page80_i111
#CELL
  pure_quanta q_res *
  page80_i112
#CELL
  pure_quanta q_res *
  page80_i113
#CELL
  pure_quanta q_res *
  page80_i114
#CELL
  pure_quanta q_res *
  page80_i115
#CELL
  pure_quanta q_res *
  page80_i116
#CELL
  pure_quanta q_res *
  page80_i117
#CELL
  pure_quanta q_res *
  page80_i118
#CELL
  pure_quanta q_res *
  page80_i119
#ISCELL
  standard offpage *
  page80_i12
#CELL
  pure_quanta q_res *
  page80_i120
#CELL
  pure_quanta q_res *
  page80_i121
#CELL
  pure_quanta q_res *
  page80_i122
#CELL
  pure_quanta q_res *
  page80_i123
#ISCELL
  standard offpage *
  page80_i124
#CELL
  pure_quanta q_res *
  page80_i125
#CELL
  pure_quanta q_res *
  page80_i126
#CELL
  pure_quanta q_res *
  page80_i127
#CELL
  pure_quanta q_res *
  page80_i128
#CELL
  pure_quanta q_res *
  page80_i129
#ISCELL
  standard offpage *
  page80_i13
#CELL
  pure_quanta q_res *
  page80_i130
#CELL
  pure_quanta q_res *
  page80_i131
#ISCELL
  standard offpage *
  page80_i132
#ISCELL
  standard offpage *
  page80_i133
#ISCELL
  standard offpage *
  page80_i134
#ISCELL
  standard offpage *
  page80_i135
#ISCELL
  standard offpage *
  page80_i136
#ISCELL
  standard offpage *
  page80_i137
#ISCELL
  standard offpage *
  page80_i14
#ISCELL
  standard offpage *
  page80_i140
#ISCELL
  standard offpage *
  page80_i141
#ISCELL
  standard offpage *
  page80_i142
#ISCELL
  standard offpage *
  page80_i143
#ISCELL
  standard offpage *
  page80_i144
#ISCELL
  standard offpage *
  page80_i147
#ISCELL
  standard offpage *
  page80_i148
#ISCELL
  standard offpage *
  page80_i15
#ISCELL
  standard offpage *
  page80_i151
#ISCELL
  standard offpage *
  page80_i152
#CELL
  pure_quanta q_res *
  page80_i154
#CELL
  pure_quanta q_res *
  page80_i155
#CELL
  pure_quanta q_res *
  page80_i156
#CELL
  pure_quanta q_res *
  page80_i157
#CELL
  pure_quanta q_res *
  page80_i158
#CELL
  pure_quanta q_res *
  page80_i159
#ISCELL
  standard offpage *
  page80_i16
#CELL
  pure_quanta q_res *
  page80_i160
#CELL
  pure_quanta q_res *
  page80_i161
#CELL
  pure_quanta q_res *
  page80_i162
#CELL
  pure_quanta q_res *
  page80_i163
#CELL
  pure_quanta q_res *
  page80_i164
#CELL
  pure_quanta q_res *
  page80_i165
#CELL
  pure_quanta q_res *
  page80_i166
#CELL
  pure_quanta q_res *
  page80_i167
#CELL
  pure_quanta q_res *
  page80_i168
#CELL
  pure_quanta q_res *
  page80_i169
#ISCELL
  standard offpage *
  page80_i17
#CELL
  pure_quanta q_res *
  page80_i170
#CELL
  pure_quanta q_res *
  page80_i171
#CELL
  pure_quanta q_res *
  page80_i172
#CELL
  pure_quanta q_res *
  page80_i173
#CELL
  pure_quanta q_res *
  page80_i174
#CELL
  pure_quanta q_res *
  page80_i175
#CELL
  pure_quanta q_res *
  page80_i176
#CELL
  pure_quanta q_res *
  page80_i177
#CELL
  pure_quanta q_res *
  page80_i178
#CELL
  pure_quanta q_res *
  page80_i179
#ISCELL
  standard offpage *
  page80_i18
#CELL
  pure_quanta q_res *
  page80_i180
#ISCELL
  standard offpage *
  page80_i181
#ISCELL
  standard offpage *
  page80_i182
#ISCELL
  standard offpage *
  page80_i183
#ISCELL
  standard offpage *
  page80_i184
#ISCELL
  standard offpage *
  page80_i185
#ISCELL
  standard offpage *
  page80_i186
#ISCELL
  standard offpage *
  page80_i187
#ISCELL
  standard offpage *
  page80_i188
#ISCELL
  standard offpage *
  page80_i189
#ISCELL
  standard offpage *
  page80_i19
#ISCELL
  standard offpage *
  page80_i190
#ISCELL
  standard offpage *
  page80_i191
#ISCELL
  standard offpage *
  page80_i192
#ISCELL
  standard offpage *
  page80_i193
#ISCELL
  standard offpage *
  page80_i194
#ISCELL
  standard offpage *
  page80_i195
#ISCELL
  standard offpage *
  page80_i196
#ISCELL
  standard offpage *
  page80_i197
#ISCELL
  standard offpage *
  page80_i198
#ISCELL
  standard offpage *
  page80_i199
#ISCELL
  standard offpage *
  page80_i2
#ISCELL
  standard offpage *
  page80_i20
#ISCELL
  standard offpage *
  page80_i200
#ISCELL
  standard offpage *
  page80_i201
#ISCELL
  standard offpage *
  page80_i202
#ISCELL
  standard offpage *
  page80_i203
#ISCELL
  standard offpage *
  page80_i204
#ISCELL
  standard offpage *
  page80_i206
#ISCELL
  standard offpage *
  page80_i207
#ISCELL
  standard offpage *
  page80_i209
#ISCELL
  standard offpage *
  page80_i21
#ISCELL
  standard offpage *
  page80_i210
#ISCELL
  standard offpage *
  page80_i211
#ISCELL
  standard offpage *
  page80_i212
#ISCELL
  standard offpage *
  page80_i213
#ISCELL
  standard offpage *
  page80_i214
#CELL
  pure_quanta q_res *
  page80_i215
#CELL
  pure_quanta lcmxo3lf9400c5bg484c *
  page80_i216
#CELL
  pure_quanta lcmxo3lf9400c5bg484c *
  page80_i217
#ISCELL
  standard offpage *
  page80_i218
#ISCELL
  standard offpage *
  page80_i219
#CELL
  pure_quanta q_res *
  page80_i22
#CELL
  pure_quanta q_res *
  page80_i220
#ISCELL
  standard offpage *
  page80_i221
#ISCELL
  standard offpage *
  page80_i222
#CELL
  pure_quanta q_res *
  page80_i223
#CELL
  pure_quanta q_res *
  page80_i224
#ISCELL
  standard offpage *
  page80_i225
#CELL
  pure_quanta q_res *
  page80_i226
#ISCELL
  standard offpage *
  page80_i227
#CELL
  pure_quanta q_res *
  page80_i228
#ISCELL
  standard offpage *
  page80_i229
#CELL
  pure_quanta q_res *
  page80_i231
#ISCELL
  standard offpage *
  page80_i232
#CELL
  pure_quanta q_res *
  page80_i233
#ISCELL
  standard offpage *
  page80_i234
#ISCELL
  standard offpage *
  page80_i235
#ISCELL
  standard offpage *
  page80_i239
#CELL
  pure_quanta q_res *
  page80_i240
#ISCELL
  standard offpage *
  page80_i241
#CELL
  pure_quanta q_res *
  page80_i242
#CELL
  pure_quanta q_res *
  page80_i243
#ISCELL
  standard offpage *
  page80_i244
#ISCELL
  standard offpage *
  page80_i245
#CELL
  pure_quanta q_res *
  page80_i246
#CELL
  pure_quanta q_res *
  page80_i247
#ISCELL
  standard offpage *
  page80_i248
#ISCELL
  standard offpage *
  page80_i249
#CELL
  pure_quanta q_res *
  page80_i25
#CELL
  pure_quanta q_res *
  page80_i250
#CELL
  pure_quanta q_res *
  page80_i251
#ISCELL
  standard offpage *
  page80_i252
#ISCELL
  standard offpage *
  page80_i253
#CELL
  pure_quanta q_res *
  page80_i254
#CELL
  pure_quanta q_res *
  page80_i255
#ISCELL
  standard offpage *
  page80_i256
#ISCELL
  standard offpage *
  page80_i257
#CELL
  pure_quanta q_res *
  page80_i258
#CELL
  pure_quanta q_res *
  page80_i259
#ISCELL
  standard offpage *
  page80_i260
#ISCELL
  standard offpage *
  page80_i261
#CELL
  pure_quanta q_res *
  page80_i262
#CELL
  pure_quanta q_res *
  page80_i263
#ISCELL
  standard offpage *
  page80_i264
#ISCELL
  standard offpage *
  page80_i265
#CELL
  pure_quanta q_res *
  page80_i266
#ISCELL
  standard offpage *
  page80_i267
#CELL
  pure_quanta q_res *
  page80_i268
#ISCELL
  standard offpage *
  page80_i269
#ISCELL
  standard offpage *
  page80_i270
#CELL
  pure_quanta q_res *
  page80_i271
#CELL
  pure_quanta q_res *
  page80_i272
#ISCELL
  standard offpage *
  page80_i273
#CELL
  pure_quanta q_res *
  page80_i274
#ISCELL
  standard offpage *
  page80_i275
#CELL
  pure_quanta q_res *
  page80_i276
#CELL
  pure_quanta q_res *
  page80_i278
#ISCELL
  standard offpage *
  page80_i279
#CELL
  pure_quanta q_res *
  page80_i28
#ISCELL
  standard offpage *
  page80_i280
#CELL
  pure_quanta q_res *
  page80_i281
#CELL
  pure_quanta q_res *
  page80_i284
#ISCELL
  standard offpage *
  page80_i285
#CELL
  pure_quanta q_res *
  page80_i286
#ISCELL
  standard offpage *
  page80_i287
#CELL
  pure_quanta q_res *
  page80_i288
#ISCELL
  standard offpage *
  page80_i289
#CELL
  pure_quanta q_res *
  page80_i29
#CELL
  pure_quanta q_res *
  page80_i290
#ISCELL
  standard offpage *
  page80_i291
#ISCELL
  standard offpage *
  page80_i292
#CELL
  pure_quanta q_res *
  page80_i293
#CELL
  pure_quanta q_res *
  page80_i294
#CELL
  pure_quanta q_res *
  page80_i295
#ISCELL
  standard offpage *
  page80_i296
#ISCELL
  standard offpage *
  page80_i297
#CELL
  pure_quanta q_res *
  page80_i298
#ISCELL
  pure_quanta_power universal_power *
  page80_i299
#CELL
  pure_quanta q_res *
  page80_i30
#CELL
  pure_quanta q_res *
  page80_i301
#ISCELL
  standard offpage *
  page80_i302
#CELL
  pure_quanta q_res *
  page80_i303
#ISCELL
  standard offpage *
  page80_i304
#ISCELL
  standard offpage *
  page80_i305
#ISCELL
  standard offpage *
  page80_i306
#ISCELL
  standard offpage *
  page80_i308
#ISCELL
  standard offpage *
  page80_i309
#CELL
  pure_quanta q_res *
  page80_i31
#ISCELL
  standard offpage *
  page80_i310
#CELL
  pure_quanta q_res *
  page80_i311
#ISCELL
  standard offpage *
  page80_i312
#ISCELL
  standard offpage *
  page80_i313
#ISCELL
  standard offpage *
  page80_i314
#CELL
  pure_quanta q_res *
  page80_i315
#ISCELL
  standard offpage *
  page80_i316
#ISCELL
  standard offpage *
  page80_i317
#CELL
  pure_quanta q_res *
  page80_i318
#CELL
  pure_quanta q_res *
  page80_i319
#CELL
  pure_quanta q_res *
  page80_i32
#ISCELL
  standard offpage *
  page80_i320
#ISCELL
  standard offpage *
  page80_i321
#CELL
  pure_quanta q_res *
  page80_i322
#ISCELL
  standard offpage *
  page80_i323
#CELL
  pure_quanta q_res *
  page80_i324
#ISCELL
  standard offpage *
  page80_i325
#CELL
  pure_quanta q_res *
  page80_i326
#CELL
  pure_quanta q_res *
  page80_i327
#ISCELL
  standard offpage *
  page80_i328
#ISCELL
  standard offpage *
  page80_i329
#CELL
  pure_quanta q_res *
  page80_i33
#CELL
  pure_quanta q_res *
  page80_i330
#ISCELL
  standard offpage *
  page80_i331
#CELL
  pure_quanta q_res *
  page80_i332
#ISCELL
  standard offpage *
  page80_i333
#CELL
  pure_quanta q_res *
  page80_i334
#CELL
  pure_quanta q_res *
  page80_i335
#ISCELL
  standard offpage *
  page80_i336
#ISCELL
  standard offpage *
  page80_i337
#CELL
  pure_quanta q_res *
  page80_i338
#CELL
  pure_quanta q_res *
  page80_i339
#CELL
  pure_quanta q_res *
  page80_i34
#ISCELL
  standard offpage *
  page80_i340
#ISCELL
  standard offpage *
  page80_i341
#CELL
  pure_quanta q_res *
  page80_i342
#CELL
  pure_quanta q_res *
  page80_i343
#CELL
  pure_quanta q_res *
  page80_i344
#CELL
  pure_quanta q_res *
  page80_i345
#ISCELL
  standard offpage *
  page80_i346
#ISCELL
  standard offpage *
  page80_i347
#ISCELL
  standard offpage *
  page80_i348
#ISCELL
  standard offpage *
  page80_i349
#CELL
  pure_quanta q_res *
  page80_i35
#CELL
  pure_quanta q_res *
  page80_i350
#CELL
  pure_quanta q_res *
  page80_i351
#CELL
  pure_quanta q_res *
  page80_i352
#CELL
  pure_quanta q_res *
  page80_i353
#ISCELL
  standard offpage *
  page80_i354
#ISCELL
  standard offpage *
  page80_i355
#ISCELL
  standard offpage *
  page80_i356
#ISCELL
  standard offpage *
  page80_i357
#ISCELL
  standard offpage *
  page80_i358
#ISCELL
  standard offpage *
  page80_i359
#CELL
  pure_quanta q_res *
  page80_i36
#CELL
  pure_quanta q_res *
  page80_i360
#ISCELL
  standard offpage *
  page80_i361
#CELL
  pure_quanta q_res *
  page80_i362
#ISCELL
  standard offpage *
  page80_i363
#CELL
  pure_quanta q_res *
  page80_i364
#ISCELL
  standard offpage *
  page80_i365
#CELL
  pure_quanta q_res *
  page80_i366
#ISCELL
  standard offpage *
  page80_i367
#ISCELL
  standard offpage *
  page80_i37
#ISCELL
  standard offpage *
  page80_i40
#ISCELL
  standard offpage *
  page80_i41
#ISCELL
  standard offpage *
  page80_i42
#ISCELL
  standard offpage *
  page80_i43
#ISCELL
  standard offpage *
  page80_i46
#ISCELL
  standard offpage *
  page80_i47
#ISCELL
  standard offpage *
  page80_i49
#ISCELL
  standard offpage *
  page80_i5
#ISCELL
  standard offpage *
  page80_i50
#ISCELL
  standard offpage *
  page80_i51
#ISCELL
  standard offpage *
  page80_i52
#ISCELL
  standard offpage *
  page80_i53
#ISCELL
  standard offpage *
  page80_i54
#ISCELL
  standard offpage *
  page80_i55
#ISCELL
  standard offpage *
  page80_i56
#CELL
  pure_quanta q_res *
  page80_i57
#CELL
  pure_quanta q_res *
  page80_i58
#CELL
  pure_quanta q_res *
  page80_i59
#ISCELL
  standard offpage *
  page80_i6
#CELL
  pure_quanta q_res *
  page80_i60
#CELL
  pure_quanta q_res *
  page80_i61
#CELL
  pure_quanta q_res *
  page80_i62
#CELL
  pure_quanta q_res *
  page80_i63
#CELL
  pure_quanta q_res *
  page80_i64
#CELL
  pure_quanta q_res *
  page80_i65
#CELL
  pure_quanta q_res *
  page80_i66
#CELL
  pure_quanta q_res *
  page80_i67
#CELL
  pure_quanta q_res *
  page80_i68
#ISCELL
  standard offpage *
  page80_i69
#ISCELL
  standard offpage *
  page80_i70
#ISCELL
  standard offpage *
  page80_i71
#ISCELL
  standard offpage *
  page80_i72
#ISCELL
  standard offpage *
  page80_i73
#ISCELL
  standard offpage *
  page80_i74
#ISCELL
  standard offpage *
  page80_i75
#ISCELL
  standard offpage *
  page80_i76
#ISCELL
  standard offpage *
  page80_i77
#ISCELL
  standard offpage *
  page80_i78
#ISCELL
  standard offpage *
  page80_i79
#ISCELL
  standard offpage *
  page80_i80
#ISCELL
  standard offpage *
  page80_i81
#ISCELL
  standard offpage *
  page80_i82
#ISCELL
  standard offpage *
  page80_i83
#ISCELL
  standard offpage *
  page80_i84
#ISCELL
  standard offpage *
  page80_i85
#ISCELL
  standard offpage *
  page80_i86
#ISCELL
  standard offpage *
  page80_i88
#ISCELL
  standard offpage *
  page80_i89
#ISCELL
  standard offpage *
  page80_i9
#ISCELL
  standard offpage *
  page80_i90
#ISCELL
  standard offpage *
  page80_i91
#ISCELL
  standard offpage *
  page80_i92
#ISCELL
  standard offpage *
  page80_i93
#ISCELL
  standard offpage *
  page80_i94
#ISCELL
  standard offpage *
  page80_i95
#ISCELL
  standard offpage *
  page80_i96
#ISCELL
  standard offpage *
  page80_i97
#ISCELL
  standard offpage *
  page80_i98
#ISCELL
  standard offpage *
  page80_i99
